FILE_TYPE = CONNECTIVITY;
{Allegro Design Entry HDL 16.6-p007 (v16-6-112F) 10/10/2012}
"PAGE_NUMBER" = 153;
0"NC";
1"GND\g";
2"GND\g";
3"P3V3_STBY\g";
4"P3V3_STBY\g";
5"GND\g";
6"P3V3_STBY\g";
7"GND\g";
8"P3V3_STBY\g";
9"P3V3_STBY\g";
10"GND\g";
11"GND\g";
12"P3V3_STBY\g";
13"PU_BIOS_SPI_HOLD0_N";
14"PU_BIOS_SPI_WP0_N";
15"PU_BIOS_SPI_HOLD1_N";
16"PU_BIOS_SPI_WP1_N";
17"TP_SPI_1_1";
18"TP_SPI_1_5";
19"TP_SPI_0_1";
20"TP_SPI_0_0";
21"TP_SPI_0_2";
22"TP_SPI_1_0";
23"TP_SPI_1_6";
24"TP_SPI_0_3";
25"TP_SPI_0_5";
26"TP_SPI_0_6";
27"TP_SPI_1_2";
28"TP_SPI_1_3";
29"TP_SPI_1_4";
30"TP_SPI_0_4";
31"SPI_CS0_PRIMARY_R_N";
32"PU_SPI0_RST";
33"PU_BIOS_SPI_HOLD0_N";
34"PU_BIOS_SPI_WP0_N";
35"PU_SPI1_RST";
36"PU_BIOS_SPI_HOLD1_N";
37"PU_BIOS_SPI_WP1_N";
38"SPI_MISO_R1";
39"SPI_CS0_SECONDARY_R_N";
40"SPI_SWITCH_MOSI_R1";
41"SPI_CLK_R0";
42"SPI_MISO_R0";
43"SPI_SWITCH_MOSI_R0";
44"SPI_CLK_R1";
45"SPI_SWITCH_CLK";
46"SPI_SWITCH_MISO";
47"SPI_SWITCH_MOSI";
48"SPI_BIOS_SOCKET_IO2";
49"SPI_BIOS_SOCKET_IO3";
50"SPI_SWITCH_MISO";
51"SPI_SWITCH_CLK";
52"SPI_SWITCH_MOSI";
53"SPI_BIOS_SOCKET_IO2";
54"SPI_BIOS_SOCKET_IO3";
%"RES"
"1","(-6500,3600)","0","mstr_discrete","I108";
;
CDS_LOCATION"R7F37"
CDS_SEC"1"
$SEC"1"
CDS_LIB"mstr_discrete"
BOM_COST"MIO_BIOS_MEM"
ROOM"SB_SPI"
PACK_TYPE"0402"
LOCATION"R7F37"
MATERIAL"CHIP"
TOLERANCE"1%"
PART_NUMBER"G21796-074"
VALUE"33.2"
WATTAGE"1/16W";
"B"
$PN"2"34;
"A"
$PN"1"48;
%"RES"
"1","(-6475,3325)","0","mstr_discrete","I109";
;
BOM_COST"MIO_BIOS_MEM"
CDS_LOCATION"R7F3"
NO_XNET_CONNECTION"1"
CDS_SEC"1"
ROOM"SB_SPI"
$SEC"1"
CDS_LIB"mstr_discrete"
PACK_TYPE"0402"
MATERIAL"CHIP"
TOLERANCE"1%"
LOCATION"R7F3"
PART_NUMBER"G21796-074"
VALUE"33.2"
WATTAGE"1/16W";
"B"
$PN"2"33;
"A"
$PN"1"49;
%"CAP_A"
"1","(-4075,4500)","0","dev_discrete","I130";
;
ROOM"SB_SPI"
SEC"1"
SEC_TYPE"0402V"
CDS_SEC"1"
BOM_COST"MIO_BIOS_MEM"
NO_XNET_CONNECTION"1"
CDS_LOCATION"C7F2"
CDS_LIB"dev_discrete"
LOCATION"C7F2"
PART_NUMBER"D97712-004"
MATERIAL"X6S"
VOLTAGE"6.3V"
TOLERANCE"10%"
VALUE"1.0UF"
PACK_TYPE"0402V";
"B"
$PN"2"1;
"A"
$PN"1"12;
%"CAP_A"
"1","(-3775,4500)","0","dev_discrete","I131";
;
ROOM"SB_SPI"
SEC"1"
SEC_TYPE"0402V"
CDS_SEC"1"
BOM_COST"MIO_BIOS_MEM"
NO_XNET_CONNECTION"1"
CDS_LOCATION"C7F1"
CDS_LIB"dev_discrete"
PART_NUMBER"A36096-045"
VALUE"0.01UF"
PACK_TYPE"0402V"
LOCATION"C7F1"
TOLERANCE"10%"
VOLTAGE"25V"
MATERIAL"X7R";
"B"
$PN"2"1;
"A"
$PN"1"12;
%"GND"
"1","(-3775,4175)","0","mstr_symbols","I133";
;
HDL_POWER"GND"
SIZE"1B"
VOLTAGE"0.0V"
CDS_LIB"mstr_symbols"
BODY_TYPE"PLUMBING";
"A\NAC"1;
%"CAP_A"
"1","(-3625,2400)","0","dev_discrete","I136";
;
SEC"1"
SEC_TYPE"0402V"
NO_XNET_CONNECTION"1"
BOM_COST"MIO_BIOS_MEM"
CDS_SEC"1"
ROOM"SB_SPI"
CDS_LOCATION"C3T5"
CDS_LIB"dev_discrete"
VALUE"0.01UF"
PART_NUMBER"A36096-045"
LOCATION"C3T5"
TOLERANCE"10%"
PACK_TYPE"0402V"
VOLTAGE"25V"
MATERIAL"X7R";
"B"
$PN"2"2;
"A"
$PN"1"4;
%"CAP_A"
"1","(-3925,2400)","0","dev_discrete","I138";
;
NO_XNET_CONNECTION"1"
BOM_COST"MIO_BIOS_MEM"
CDS_SEC"1"
$SEC"1"
ROOM"SB_SPI"
CDS_LIB"dev_discrete"
CDS_LOCATION"C3T4"
LOCATION"C3T4"
PART_NUMBER"D97712-004"
VALUE"1.0UF"
TOLERANCE"10%"
PACK_TYPE"0402V"
VOLTAGE"6.3V"
MATERIAL"X6S";
"B"
$PN"2"2;
"A"
$PN"1"4;
%"GND"
"1","(-3625,2100)","0","mstr_symbols","I139";
;
SIZE"1B"
HDL_POWER"GND"
VOLTAGE"0.0V"
CDS_LIB"mstr_symbols"
BODY_TYPE"PLUMBING";
"A\NAC"2;
%"RES"
"1","(-1450,4425)","0","mstr_discrete","I140";
;
CDS_SEC"1"
NO_XNET_CONNECTION"1"
SEC"1"
SEC_TYPE"0402"
BOM_COST"MIO_BIOS_MEM"
CDS_LIB"mstr_discrete"
ROOM"SB_SPI"
CDS_LOCATION"R7F32"
MATERIAL"CHIP"
PACK_TYPE"0402"
LOCATION"R7F32"
WATTAGE"1/16W"
PART_NUMBER"G21796-016"
VALUE"10.0K"
TOLERANCE"1%";
"B"
$PN"2"13;
"A"
$PN"1"3;
%"P3V3_STBY"
"1","(-1750,4625)","0","mstr_symbols","I141";
;
SIZE"1B"
CDS_LIB"mstr_symbols"
VOLTAGE"3.3V"
BODY_TYPE"PLUMBING"
HDL_POWER"P3V3_STBY";
"G\NAC"3;
%"W25Q256"
"1","(-4900,3975)","0","mstr_memory","I146";
;
CDS_SEC"1"
SEC_TYPE"XSOI"
SEC"1"
ROOM"SB_SPI"
CDS_LOCATION"U7F1"
BOM_COST"MIO_BIOS_MEM"
PACK_TYPE"XSOI"
CDS_LIB"mstr_memory"
LOCATION"U7F1"
MATERIAL"IC"
PART_NUMBER"H25002-001";
"HOLD_N_IO<3>"
$PN"1"33;
"RESET_N"
$PN"3"32;
"DI_IO<0>"
$PN"15"43;
"CS_N"
$PN"7"31;
"VCC"
$PN"2"12;
"CLK"
$PN"16"41;
"DO_IO<1>"
$PN"8"42;
"GND"
$PN"10"11;
"NC<6>"
$PN"4"26;
"NC<5>"
$PN"5"25;
"NC<4>"
$PN"6"30;
"NC<3>"
$PN"11"24;
"NC<2>"
$PN"12"21;
"NC<1>"
$PN"13"19;
"NC<0>"
$PN"14"20;
"WP_N_IO<2>"
$PN"9"34;
%"RES"
"2","(-5875,2325)","2","mstr_discrete","I150";
;
CDS_SEC"1"
SEC_TYPE"0402"
BOM_COST"MIO_BIOS_MEM"
SEC"1"
NO_XNET_CONNECTION"1"
CDS_LIB"mstr_discrete"
ROOM"SB_SPI"
CDS_LOCATION"R3T3"
LOCATION"R3T3"
MATERIAL"EMPTY"
VALUE"4.75K"
TOLERANCE"1%"
PACK_TYPE"0402"
WATTAGE"1/16W"
PART_NUMBER"G21796-072";
"A"
$PN"1"4;
"B"
$PN"2"35;
%"P3V3_STBY"
"1","(-6375,2725)","0","mstr_symbols","I151";
;
VOLTAGE"3.3V"
SIZE"1B"
CDS_LIB"mstr_symbols"
BODY_TYPE"PLUMBING"
HDL_POWER"P3V3_STBY";
"G\NAC"4;
%"RES"
"2","(-6175,2325)","2","mstr_discrete","I152";
;
CDS_SEC"1"
SEC_TYPE"0402"
BOM_COST"MIO_BIOS_MEM"
SEC"1"
NO_XNET_CONNECTION"1"
CDS_LOCATION"R3T5"
ROOM"SB_SPI"
CDS_LIB"mstr_discrete"
MATERIAL"CHIP"
VALUE"4.75K"
LOCATION"R3T5"
TOLERANCE"1%"
PACK_TYPE"0402"
WATTAGE"1/16W"
PART_NUMBER"G21796-072";
"A"
$PN"1"4;
"B"
$PN"2"39;
%"GND"
"1","(-4075,1500)","0","mstr_symbols","I154";
;
HDL_POWER"GND"
CDS_LIB"mstr_symbols"
VOLTAGE"0"
SIZE"1B"
BODY_TYPE"PLUMBING";
"A\NAC"5;
%"RES"
"1","(-6200,1875)","0","mstr_discrete","I155";
;
CDS_SEC"1"
MATERIAL"CHIP"
BOM_COST"MIO_BIOS_MEM"
ROOM"SB_SPI"
CDS_LOCATION"R3T2"
PACK_TYPE"0402"
TOLERANCE"1%"
SEC"1"
SEC_TYPE"0402"
PART_NUMBER"G21796-074"
CDS_LIB"mstr_discrete"
WATTAGE"1/16W"
LOCATION"R3T2"
VALUE"33.2";
"B"
$PN"2"38;
"A"
$PN"1"50;
%"RES"
"1","(-6425,1500)","0","mstr_discrete","I156";
;
NO_XNET_CONNECTION"1"
$SEC"1"
CDS_SEC"1"
BOM_COST"MIO_BIOS_MEM"
ROOM"SB_SPI"
CDS_LOCATION"R3U1"
CDS_LIB"mstr_discrete"
PACK_TYPE"0402"
LOCATION"R3U1"
MATERIAL"CHIP"
PART_NUMBER"G21796-074"
TOLERANCE"1%"
VALUE"33.2"
WATTAGE"1/16W";
"B"
$PN"2"37;
"A"
$PN"1"53;
%"RES"
"1","(-6400,1225)","0","mstr_discrete","I157";
;
CDS_LIB"mstr_discrete"
ROOM"SB_SPI"
BOM_COST"MIO_BIOS_MEM"
NO_XNET_CONNECTION"1"
$SEC"1"
CDS_SEC"1"
CDS_LOCATION"R3T1"
PACK_TYPE"0402"
MATERIAL"CHIP"
TOLERANCE"1%"
LOCATION"R3T1"
PART_NUMBER"G21796-074"
VALUE"33.2"
WATTAGE"1/16W";
"B"
$PN"2"36;
"A"
$PN"1"54;
%"W25Q256"
"1","(-4825,1875)","0","mstr_memory","I165";
;
CDS_SEC"1"
SEC"1"
SEC_TYPE"XSOI"
PACK_TYPE"XSOI"
BOM_COST"MIO_BIOS_MEM"
CDS_LOCATION"U3T1"
ROOM"SB_SPI"
CDS_LIB"mstr_memory"
LOCATION"U3T1"
MATERIAL"IC"
PART_NUMBER"H25002-001";
"HOLD_N_IO<3>"
$PN"1"36;
"RESET_N"
$PN"3"35;
"DI_IO<0>"
$PN"15"40;
"CS_N"
$PN"7"39;
"VCC"
$PN"2"4;
"CLK"
$PN"16"44;
"DO_IO<1>"
$PN"8"38;
"GND"
$PN"10"5;
"NC<6>"
$PN"4"23;
"NC<5>"
$PN"5"18;
"NC<4>"
$PN"6"29;
"NC<3>"
$PN"11"28;
"NC<2>"
$PN"12"27;
"NC<1>"
$PN"13"17;
"NC<0>"
$PN"14"22;
"WP_N_IO<2>"
$PN"9"37;
%"RES"
"1","(-6550,3825)","0","mstr_discrete","I166";
;
CDS_SEC"1"
$SEC"1"
CDS_LOCATION"R8F8"
ROOM"MIO_BIOS_MEM"
CDS_LIB"mstr_discrete"
PART_NUMBER"G21796-074"
PACK_TYPE"0402"
MATERIAL"CHIP"
LOCATION"R8F8"
TOLERANCE"1%"
VALUE"33.2"
WATTAGE"1/16W";
"B"
$PN"2"41;
"A"
$PN"1"45;
%"RES"
"1","(-6525,1725)","0","mstr_discrete","I167";
;
$SEC"1"
CDS_SEC"1"
ROOM"MIO_BIOS_MEM"
CDS_LIB"mstr_discrete"
CDS_LOCATION"R8F7"
PART_NUMBER"G21796-074"
MATERIAL"CHIP"
TOLERANCE"1%"
PACK_TYPE"0402"
LOCATION"R8F7"
VALUE"33.2"
WATTAGE"1/16W";
"B"
$PN"2"44;
"A"
$PN"1"51;
%"RES"
"2","(-1750,3925)","0","mstr_discrete","I168";
;
CDS_SEC"1"
SEC"1"
NO_XNET_CONNECTION"1"
ROOM"SB_SPI"
SEC_TYPE"0402"
BOM_COST"MIO_BIOS_MEM"
CDS_LOCATION"R7F28"
CDS_LIB"mstr_discrete"
PART_NUMBER"G21796-016"
MATERIAL"CHIP"
TOLERANCE"1%"
VALUE"10.0K"
LOCATION"R7F28"
WATTAGE"1/16W"
PACK_TYPE"0402";
"A"
$PN"1"6;
"B"
$PN"2"14;
%"P3V3_STBY"
"1","(-1750,4175)","0","mstr_symbols","I169";
;
CDS_LIB"mstr_symbols"
SIZE"1B"
VOLTAGE"3.3V"
BODY_TYPE"PLUMBING"
HDL_POWER"P3V3_STBY";
"G\NAC"6;
%"RES"
"2","(-1750,3550)","0","mstr_discrete","I170";
;
CDS_SEC"1"
BOM_COST"MIO_BIOS_MEM"
SEC_TYPE"0402"
SEC"1"
ROOM"SB_SPI"
CDS_LOCATION"R7F30"
CDS_LIB"mstr_discrete"
PART_NUMBER"G21796-016"
LOCATION"R7F30"
VALUE"10.0K"
TOLERANCE"1%"
MATERIAL"EMPTY"
PACK_TYPE"0402"
WATTAGE"1/16W";
"A"
$PN"1"14;
"B"
$PN"2"7;
%"GND"
"1","(-1750,3325)","0","mstr_symbols","I172";
;
HDL_POWER"GND"
CDS_LIB"mstr_symbols"
SIZE"1B"
VOLTAGE"0.0V"
BODY_TYPE"PLUMBING";
"A\NAC"7;
%"RES"
"1","(-1450,2325)","0","mstr_discrete","I174";
;
CDS_SEC"1"
SEC"1"
SEC_TYPE"0402"
BOM_COST"MIO_BIOS_MEM"
CDS_LIB"mstr_discrete"
CDS_LOCATION"R3T4"
ROOM"SB_SPI"
MATERIAL"CHIP"
PACK_TYPE"0402"
LOCATION"R3T4"
WATTAGE"1/16W"
PART_NUMBER"G21796-016"
VALUE"10.0K"
TOLERANCE"1%";
"B"
$PN"2"15;
"A"
$PN"1"8;
%"P3V3_STBY"
"1","(-1750,2525)","0","mstr_symbols","I175";
;
SIZE"1B"
CDS_LIB"mstr_symbols"
VOLTAGE"3.3V"
BODY_TYPE"PLUMBING"
HDL_POWER"P3V3_STBY";
"G\NAC"8;
%"P3V3_STBY"
"1","(-1750,2075)","0","mstr_symbols","I176";
;
CDS_LIB"mstr_symbols"
SIZE"1B"
VOLTAGE"3.3V"
BODY_TYPE"PLUMBING"
HDL_POWER"P3V3_STBY";
"G\NAC"9;
%"RES"
"2","(-1750,1825)","0","mstr_discrete","I178";
;
CDS_SEC"1"
ROOM"SB_SPI"
SEC"1"
BOM_COST"MIO_BIOS_MEM"
SEC_TYPE"0402"
CDS_LOCATION"R3T12"
CDS_LIB"mstr_discrete"
PART_NUMBER"G21796-016"
WATTAGE"1/16W"
TOLERANCE"1%"
VALUE"10.0K"
LOCATION"R3T12"
MATERIAL"CHIP"
PACK_TYPE"0402";
"A"
$PN"1"9;
"B"
$PN"2"16;
%"RES"
"2","(-1750,1450)","0","mstr_discrete","I179";
;
CDS_SEC"1"
BOM_COST"MIO_BIOS_MEM"
SEC_TYPE"0402"
SEC"1"
ROOM"SB_SPI"
CDS_LOCATION"R3T9"
CDS_LIB"mstr_discrete"
PART_NUMBER"G21796-016"
LOCATION"R3T9"
VALUE"10.0K"
MATERIAL"EMPTY"
TOLERANCE"1%"
WATTAGE"1/16W"
PACK_TYPE"0402";
"A"
$PN"1"16;
"B"
$PN"2"10;
%"GND"
"1","(-1750,1225)","0","mstr_symbols","I180";
;
HDL_POWER"GND"
CDS_LIB"mstr_symbols"
SIZE"1B"
VOLTAGE"0.0V"
BODY_TYPE"PLUMBING";
"A\NAC"10;
%"RES"
"1","(-6525,3925)","0","mstr_discrete","I181";
;
CDS_SEC"1"
SEC_TYPE"0402"
SEC"1"
MATERIAL"CHIP"
BOM_COST"MIO_BIOS_MEM"
ROOM"SB_SPI"
PACK_TYPE"0402"
CDS_LIB"mstr_discrete"
CDS_LOCATION"R7F29"
PART_NUMBER"G21796-074"
TOLERANCE"1%"
WATTAGE"1/16W"
LOCATION"R7F29"
VALUE"33.2";
"B"
$PN"2"43;
"A"
$PN"1"47;
%"RES"
"1","(-6450,1825)","0","mstr_discrete","I184";
;
CDS_SEC"1"
SEC"1"
SEC_TYPE"0402"
MATERIAL"CHIP"
BOM_COST"MIO_BIOS_MEM"
ROOM"SB_SPI"
PACK_TYPE"0402"
TOLERANCE"1%"
CDS_LOCATION"R3T10"
CDS_LIB"mstr_discrete"
PART_NUMBER"G21796-074"
WATTAGE"1/16W"
VALUE"33.2"
LOCATION"R3T10";
"B"
$PN"2"40;
"A"
$PN"1"52;
%"RES"
"2","(-5950,4425)","2","mstr_discrete","I90";
;
CDS_SEC"1"
BOM_COST"MIO_BIOS_MEM"
SEC_TYPE"0402"
SEC"1"
NO_XNET_CONNECTION"1"
ROOM"SB_SPI"
CDS_LOCATION"R7F6"
CDS_LIB"mstr_discrete"
MATERIAL"EMPTY"
LOCATION"R7F6"
VALUE"4.75K"
TOLERANCE"1%"
WATTAGE"1/16W"
PACK_TYPE"0402"
PART_NUMBER"G21796-072";
"A"
$PN"1"12;
"B"
$PN"2"32;
%"GND"
"1","(-4150,3600)","0","mstr_symbols","I91";
;
SIZE"1B"
CDS_LIB"mstr_symbols"
HDL_POWER"GND"
VOLTAGE"0"
BODY_TYPE"PLUMBING";
"A\NAC"11;
%"RES"
"2","(-6250,4425)","2","mstr_discrete","I94";
;
CDS_SEC"1"
NO_XNET_CONNECTION"1"
SEC"1"
BOM_COST"MIO_BIOS_MEM"
SEC_TYPE"0402"
ROOM"SB_SPI"
CDS_LIB"mstr_discrete"
CDS_LOCATION"R7F5"
MATERIAL"CHIP"
TOLERANCE"1%"
LOCATION"R7F5"
PART_NUMBER"G21796-072"
VALUE"4.75K"
PACK_TYPE"0402"
WATTAGE"1/16W";
"A"
$PN"1"12;
"B"
$PN"2"31;
%"P3V3_STBY"
"1","(-6450,4825)","0","mstr_symbols","I95";
;
BODY_TYPE"PLUMBING"
SIZE"1B"
CDS_LIB"mstr_symbols"
VOLTAGE"3.3V"
HDL_POWER"P3V3_STBY";
"G\NAC"12;
%"RES"
"1","(-6275,3975)","0","mstr_discrete","I98";
;
CDS_SEC"1"
SEC_TYPE"0402"
SEC"1"
PART_NUMBER"G21796-074"
BOM_COST"MIO_BIOS_MEM"
ROOM"SB_SPI"
MATERIAL"CHIP"
PACK_TYPE"0402"
CDS_LOCATION"R7F4"
CDS_LIB"mstr_discrete"
WATTAGE"1/16W"
TOLERANCE"1%"
LOCATION"R7F4"
VALUE"33.2";
"B"
$PN"2"42;
"A"
$PN"1"46;
END.
